# S9S_MB_2U (Grand Teton) — schematic netlist excerpt (pin names and nets, part order shuffled) for the footprints in the layout excerpt that follows; sources: Cadence DE-HDL packaged netlist, KiCad conversion of 03242023_DA0F0TMBIJ0_F0T_Motherboard_J_brd_V01_OCP.brd

PR1131  Q_RES  2K 0.1% CHIP  pkg 0402LF  page 301 : A = HSC_CS ; B = AGND_HSC
PR1795  Q_RES  3.3 1% CHIP  pkg 0402LF  page 293 : A = SW_PVCCINFAON_CPU1_BOOT2 ; B = SW_PVCCINFAON_CPU1_BOOT2_R

U99  RT9818C44GV  RT9818C-44GV IC  pkg SOT23_123_2-89X1-6  page 260
  \reset#\  = PWRGD_P5V
  GND  = GND
  VDD  = P5V

(kicad_pcb
	(version 20260206)
	(generator "pcbnew")
	(generator_version "10.0")
	(general
		(thickness 1.6)
		(legacy_teardrops no)
	)
	(paper "A4")
	(title_block
		(title "03242023_DA0F0TMBIJ0_F0T_Motherboard_J_brd_V01_OCP.brd")
		(comment 1 "Grand Teton / footprints 1625-1627 of 6105")
	)
	(layers
		(0 "F.Cu" signal "TOP")
		(4 "In1.Cu" signal "GND")
		(6 "In2.Cu" signal "IN1")
		(8 "In3.Cu" signal "GND1")
		(10 "In4.Cu" signal "IN2")
		(12 "In5.Cu" signal "GND2")
		(14 "In6.Cu" signal "IN3")
		(16 "In7.Cu" signal "GND3")
		(18 "In8.Cu" signal "VCC")
		(20 "In9.Cu" signal "VCC1")
		(22 "In10.Cu" signal "GND4")
		(24 "In11.Cu" signal "IN4")
		(26 "In12.Cu" signal "GND5")
		(28 "In13.Cu" signal "IN5")
		(30 "In14.Cu" signal "GND6")
		(32 "In15.Cu" signal "IN6")
		(34 "In16.Cu" signal "GND7")
		(2 "B.Cu" signal "BOTTOM")
		(9 "F.Adhes" user "F.Adhesive")
		(11 "B.Adhes" user "B.Adhesive")
		(13 "F.Paste" user "Package Geometry/Pastemask Top")
		(15 "B.Paste" user "Package Geometry/Pastemask Bottom")
		(5 "F.SilkS" user "Ref Des/Silkscreen Top")
		(7 "B.SilkS" user "Ref Des/Silkscreen Bottom")
		(1 "F.Mask" user "Board Geometry/Soldermask Top")
		(3 "B.Mask" user "Board Geometry/Soldermask Bottom")
		(17 "Dwgs.User" user "User.Drawings")
		(19 "Cmts.User" user "User.Comments")
		(21 "Eco1.User" user "User.Eco1")
		(23 "Eco2.User" user "User.Eco2")
		(25 "Edge.Cuts" user "Board Geometry/Outline")
		(27 "Margin" user)
		(31 "F.CrtYd" user "Package Geometry/Place Bound Top")
		(29 "B.CrtYd" user "Package Geometry/Place Bound Bottom")
		(35 "F.Fab" user "Ref Des/Assembly Top")
		(33 "B.Fab" user "Ref Des/Assembly Bottom")
	)
	(footprint ""
		(layer "F.Cu")
		(at 50.43551 -148.536914 180)
		(property "Reference" "PR1795"
			(at 0 0 180)
			(layer "F.SilkS")
			(hide yes)
			(effects
				(font
					(size 1.27 1.27)
				)
			)
		)
		(property "Value" ""
			(at 0 0 180)
			(layer "F.Fab")
			(effects
				(font
					(size 1.27 1.27)
				)
			)
		)
		(duplicate_pad_numbers_are_jumpers no)
		(fp_line
			(start 0.7874 0.4064)
			(end -0.7874 0.4064)
			(stroke
				(width 0.1524)
				(type default)
			)
			(layer "F.SilkS")
		)
		(fp_line
			(start 0.7874 -0.4064)
			(end 0.7874 0.4064)
			(stroke
				(width 0.1524)
				(type default)
			)
			(layer "F.SilkS")
		)
		(fp_line
			(start -0.7874 0.4064)
			(end -0.7874 -0.4064)
			(stroke
				(width 0.1524)
				(type default)
			)
			(layer "F.SilkS")
		)
		(fp_line
			(start -0.7874 -0.4064)
			(end 0.7874 -0.4064)
			(stroke
				(width 0.1524)
				(type default)
			)
			(layer "F.SilkS")
		)
		(fp_line
			(start 0.67945 0.3048)
			(end 0.120396 0.3048)
			(stroke
				(width 0.1)
				(type default)
			)
			(layer "F.Fab")
		)
		(fp_line
			(start 0.67945 -0.3048)
			(end 0.67945 0.3048)
			(stroke
				(width 0.1)
				(type default)
			)
			(layer "F.Fab")
		)
		(fp_line
			(start 0.12065 -0.2794)
			(end 0.12065 -0.3048)
			(stroke
				(width 0.1)
				(type default)
			)
			(layer "F.Fab")
		)
		(fp_line
			(start 0.12065 -0.3048)
			(end 0.67945 -0.3048)
			(stroke
				(width 0.1)
				(type default)
			)
			(layer "F.Fab")
		)
		(fp_line
			(start 0.120396 0.3048)
			(end 0.120396 0.2794)
			(stroke
				(width 0.1)
				(type default)
			)
			(layer "F.Fab")
		)
		(fp_line
			(start 0.120396 0.2794)
			(end -0.12065 0.2794)
			(stroke
				(width 0.1)
				(type default)
			)
			(layer "F.Fab")
		)
		(fp_line
			(start -0.12065 0.3048)
			(end -0.67945 0.3048)
			(stroke
				(width 0.1)
				(type default)
			)
			(layer "F.Fab")
		)
		(fp_line
			(start -0.12065 0.2794)
			(end -0.12065 0.3048)
			(stroke
				(width 0.1)
				(type default)
			)
			(layer "F.Fab")
		)
		(fp_line
			(start -0.12065 -0.2794)
			(end 0.12065 -0.2794)
			(stroke
				(width 0.1)
				(type default)
			)
			(layer "F.Fab")
		)
		(fp_line
			(start -0.12065 -0.305054)
			(end -0.12065 -0.2794)
			(stroke
				(width 0.1)
				(type default)
			)
			(layer "F.Fab")
		)
		(fp_line
			(start -0.67945 0.3048)
			(end -0.67945 -0.305054)
			(stroke
				(width 0.1)
				(type default)
			)
			(layer "F.Fab")
		)
		(fp_line
			(start -0.67945 -0.305054)
			(end -0.12065 -0.305054)
			(stroke
				(width 0.1)
				(type default)
			)
			(layer "F.Fab")
		)
		(pad "1" smd circle
			(at -0.40005 0 180)
			(size 0 0)
			(layers "F.Cu" "F.Mask" "F.Paste")
			(net "SW_PVCCINFAON_CPU1_BOOT2")
		)
		(pad "2" smd circle
			(at 0.40005 0 180)
			(size 0 0)
			(layers "F.Cu" "F.Mask" "F.Paste")
			(net "SW_PVCCINFAON_CPU1_BOOT2_R")
		)
	)
	(footprint ""
		(layer "F.Cu")
		(at 179.352448 -400.223482 180)
		(property "Reference" "PR1131"
			(at 0 0 180)
			(layer "F.SilkS")
			(hide yes)
			(effects
				(font
					(size 1.27 1.27)
				)
			)
		)
		(property "Value" ""
			(at 0 0 180)
			(layer "F.Fab")
			(effects
				(font
					(size 1.27 1.27)
				)
			)
		)
		(duplicate_pad_numbers_are_jumpers no)
		(fp_line
			(start 0.7874 0.4064)
			(end -0.7874 0.4064)
			(stroke
				(width 0.1524)
				(type default)
			)
			(layer "F.SilkS")
		)
		(fp_line
			(start 0.7874 -0.4064)
			(end 0.7874 0.4064)
			(stroke
				(width 0.1524)
				(type default)
			)
			(layer "F.SilkS")
		)
		(fp_line
			(start -0.7874 0.4064)
			(end -0.7874 -0.4064)
			(stroke
				(width 0.1524)
				(type default)
			)
			(layer "F.SilkS")
		)
		(fp_line
			(start -0.7874 -0.4064)
			(end 0.7874 -0.4064)
			(stroke
				(width 0.1524)
				(type default)
			)
			(layer "F.SilkS")
		)
		(fp_line
			(start 0.67945 0.3048)
			(end 0.120396 0.3048)
			(stroke
				(width 0.1)
				(type default)
			)
			(layer "F.Fab")
		)
		(fp_line
			(start 0.67945 -0.3048)
			(end 0.67945 0.3048)
			(stroke
				(width 0.1)
				(type default)
			)
			(layer "F.Fab")
		)
		(fp_line
			(start 0.12065 -0.2794)
			(end 0.12065 -0.3048)
			(stroke
				(width 0.1)
				(type default)
			)
			(layer "F.Fab")
		)
		(fp_line
			(start 0.12065 -0.3048)
			(end 0.67945 -0.3048)
			(stroke
				(width 0.1)
				(type default)
			)
			(layer "F.Fab")
		)
		(fp_line
			(start 0.120396 0.3048)
			(end 0.120396 0.2794)
			(stroke
				(width 0.1)
				(type default)
			)
			(layer "F.Fab")
		)
		(fp_line
			(start 0.120396 0.2794)
			(end -0.12065 0.2794)
			(stroke
				(width 0.1)
				(type default)
			)
			(layer "F.Fab")
		)
		(fp_line
			(start -0.12065 0.3048)
			(end -0.67945 0.3048)
			(stroke
				(width 0.1)
				(type default)
			)
			(layer "F.Fab")
		)
		(fp_line
			(start -0.12065 0.2794)
			(end -0.12065 0.3048)
			(stroke
				(width 0.1)
				(type default)
			)
			(layer "F.Fab")
		)
		(fp_line
			(start -0.12065 -0.2794)
			(end 0.12065 -0.2794)
			(stroke
				(width 0.1)
				(type default)
			)
			(layer "F.Fab")
		)
		(fp_line
			(start -0.12065 -0.305054)
			(end -0.12065 -0.2794)
			(stroke
				(width 0.1)
				(type default)
			)
			(layer "F.Fab")
		)
		(fp_line
			(start -0.67945 0.3048)
			(end -0.67945 -0.305054)
			(stroke
				(width 0.1)
				(type default)
			)
			(layer "F.Fab")
		)
		(fp_line
			(start -0.67945 -0.305054)
			(end -0.12065 -0.305054)
			(stroke
				(width 0.1)
				(type default)
			)
			(layer "F.Fab")
		)
		(pad "1" smd circle
			(at -0.40005 0 180)
			(size 0 0)
			(layers "F.Cu" "F.Mask" "F.Paste")
			(net "HSC_CS")
		)
		(pad "2" smd circle
			(at 0.40005 0 180)
			(size 0 0)
			(layers "F.Cu" "F.Mask" "F.Paste")
			(net "AGND_HSC")
		)
	)
	(footprint ""
		(layer "F.Cu")
		(at 417.83762 -48.53178 -90)
		(property "Reference" "U99"
			(at 3.965702 1.35382 0)
			(unlocked yes)
			(layer "F.SilkS")
			(effects
				(font
					(size 0.7874 0.5842)
					(thickness 0.1524)
				)
				(justify left)
			)
		)
		(property "Value" ""
			(at 0 0 270)
			(layer "F.Fab")
			(effects
				(font
					(size 1.27 1.27)
				)
			)
		)
		(duplicate_pad_numbers_are_jumpers no)
		(fp_line
			(start -1.934972 1.5494)
			(end -1.934972 -1.5494)
			(stroke
				(width 0.1524)
				(type default)
			)
			(layer "F.SilkS")
		)
		(fp_line
			(start 1.934972 1.5494)
			(end -1.934972 1.5494)
			(stroke
				(width 0.1524)
				(type default)
			)
			(layer "F.SilkS")
		)
		(fp_line
			(start -1.934972 -1.5494)
			(end 1.934972 -1.5494)
			(stroke
				(width 0.1524)
				(type default)
			)
			(layer "F.SilkS")
		)
		(fp_line
			(start 1.934972 -1.5494)
			(end 1.934972 1.5494)
			(stroke
				(width 0.1524)
				(type default)
			)
			(layer "F.SilkS")
		)
		(fp_line
			(start -0.901446 1.5494)
			(end -0.901446 -1.5494)
			(stroke
				(width 0.1)
				(type default)
			)
			(layer "F.Fab")
		)
		(fp_line
			(start 0.901446 1.5494)
			(end -0.901446 1.5494)
			(stroke
				(width 0.1)
				(type default)
			)
			(layer "F.Fab")
		)
		(fp_line
			(start -0.901446 -1.5494)
			(end 0.901446 -1.5494)
			(stroke
				(width 0.1)
				(type default)
			)
			(layer "F.Fab")
		)
		(fp_line
			(start 0.901446 -1.5494)
			(end 0.901446 1.5494)
			(stroke
				(width 0.1)
				(type default)
			)
			(layer "F.Fab")
		)
		(pad "1" smd rect
			(at -1.299972 -0.94996 180)
			(size 0.8128 1.016)
			(layers "F.Cu" "F.Mask" "F.Paste")
			(net "PWRGD_P5V")
		)
		(pad "2" smd rect
			(at -1.299972 0.94996 180)
			(size 0.8128 1.016)
			(layers "F.Cu" "F.Mask" "F.Paste")
			(net "GND")
		)
		(pad "3" smd rect
			(at 1.299972 0 180)
			(size 0.8128 1.016)
			(layers "F.Cu" "F.Mask" "F.Paste")
			(net "P5V")
		)
	)
)
